(kicad_pcb
	(version 20260206)
	(generator "pcbnew")
	(generator_version "10.0")
	(general
		(thickness 1.6)
		(legacy_teardrops no)
	)
	(paper "A4")
	(title_block
		(title "Bryce Canyon_IOM_M2_16342-2_OCP.brd")
		(comment 1 "Bryce Canyon / footprints 578-586 of 1146")
	)
	(layers
		(0 "F.Cu" signal "TOP")
		(4 "In1.Cu" signal "L2GND")
		(6 "In2.Cu" signal "L3")
		(8 "In3.Cu" signal "L4VCC")
		(10 "In4.Cu" signal "L5VCC")
		(12 "In5.Cu" signal "L6")
		(14 "In6.Cu" signal "L7GND")
		(2 "B.Cu" signal "BOTTOM")
		(9 "F.Adhes" user "F.Adhesive")
		(11 "B.Adhes" user "B.Adhesive")
		(13 "F.Paste" user "Package Geometry/Pastemask Top")
		(15 "B.Paste" user "Package Geometry/Pastemask Bottom")
		(5 "F.SilkS" user "Ref Des/Silkscreen Top")
		(7 "B.SilkS" user "Ref Des/Silkscreen Bottom")
		(1 "F.Mask" user "Board Geometry/Soldermask Top")
		(3 "B.Mask" user "Board Geometry/Soldermask Bottom")
		(17 "Dwgs.User" user "User.Drawings")
		(19 "Cmts.User" user "User.Comments")
		(21 "Eco1.User" user "User.Eco1")
		(23 "Eco2.User" user "User.Eco2")
		(25 "Edge.Cuts" user "Board Geometry/Outline")
		(27 "Margin" user)
		(31 "F.CrtYd" user "Package Geometry/Place Bound Top")
		(29 "B.CrtYd" user "Package Geometry/Place Bound Bottom")
		(35 "F.Fab" user "Ref Des/Assembly Top")
		(33 "B.Fab" user "Ref Des/Assembly Bottom")
	)
	(footprint ""
		(layer "F.Cu")
		(at 72.22998 -163.6141 -90)
		(property "Reference" "C245"
			(at 0 0 270)
			(layer "F.SilkS")
			(hide yes)
			(effects
				(font
					(size 1.27 1.27)
				)
			)
		)
		(property "Value" "SCD1U16V2KX-3GP"
			(at 1.1811 -2.7051 270)
			(unlocked yes)
			(layer "F.Fab")
			(hide yes)
			(effects
				(font
					(size 1.016 1.016)
					(thickness 0.1524)
				)
			)
		)
		(property "Device Type" "C402H22"
			(at 1.1811 -4.2291 270)
			(unlocked yes)
			(layer "F.Fab")
			(hide yes)
			(effects
				(font
					(size 1.016 1.016)
					(thickness 0.1524)
				)
			)
		)
		(duplicate_pad_numbers_are_jumpers no)
		(fp_rect
			(start -0.4318 0.9525)
			(end 0.4318 -0.9525)
			(stroke
				(width 0)
				(type default)
			)
			(fill no)
			(layer "F.CrtYd")
		)
		(fp_rect
			(start -0.4318 0.9525)
			(end 0.4318 -0.9525)
			(stroke
				(width 0)
				(type default)
			)
			(fill no)
			(layer "F.Fab")
		)
		(pad "1" smd custom
			(at 0 -0.4445 270)
			(size 0.1524 0.1524)
			(layers "F.Cu" "F.Mask" "F.Paste")
			(net "TPS74801_P1V15_STBY_EN")
			(options
				(clearance outline)
				(anchor circle)
			)
			(primitives
				(gr_poly
					(pts
						(arc
							(start 0.3048 -0.2032)
							(mid 0.275042 -0.275042)
							(end 0.2032 -0.3048)
						)
						(arc
							(start -0.2032 -0.3048)
							(mid -0.275042 -0.275042)
							(end -0.3048 -0.2032)
						)
						(arc
							(start -0.3048 0.2032)
							(mid -0.275042 0.275042)
							(end -0.2032 0.3048)
						)
						(arc
							(start 0.2032 0.3048)
							(mid 0.275042 0.275042)
							(end 0.3048 0.2032)
						)
					)
					(width 0)
					(fill yes)
				)
			)
		)
		(pad "2" smd custom
			(at 0 0.4445 270)
			(size 0.1524 0.1524)
			(layers "F.Cu" "F.Mask" "F.Paste")
			(net "GND")
			(options
				(clearance outline)
				(anchor circle)
			)
			(primitives
				(gr_poly
					(pts
						(arc
							(start 0.3048 -0.2032)
							(mid 0.275042 -0.275042)
							(end 0.2032 -0.3048)
						)
						(arc
							(start -0.2032 -0.3048)
							(mid -0.275042 -0.275042)
							(end -0.3048 -0.2032)
						)
						(arc
							(start -0.3048 0.2032)
							(mid -0.275042 0.275042)
							(end -0.2032 0.3048)
						)
						(arc
							(start 0.2032 0.3048)
							(mid 0.275042 0.275042)
							(end 0.3048 0.2032)
						)
					)
					(width 0)
					(fill yes)
				)
			)
		)
	)
	(footprint ""
		(layer "F.Cu")
		(at 209.226912 -120.7262 180)
		(property "Reference" "R812"
			(at 0 0 180)
			(layer "F.SilkS")
			(hide yes)
			(effects
				(font
					(size 1.27 1.27)
				)
			)
		)
		(property "Value" "4K7R2F-GP"
			(at 0.064008 -3.993896 180)
			(unlocked yes)
			(layer "F.Fab")
			(hide yes)
			(effects
				(font
					(size 1.016 1.016)
					(thickness 0.1524)
				)
			)
		)
		(property "Device Type" "R402H16"
			(at 0.064008 -5.517896 180)
			(unlocked yes)
			(layer "F.Fab")
			(hide yes)
			(effects
				(font
					(size 1.016 1.016)
					(thickness 0.1524)
				)
			)
		)
		(duplicate_pad_numbers_are_jumpers no)
		(fp_line
			(start 0.508 -0.9398)
			(end -0.508 -0.9398)
			(stroke
				(width 0.1524)
				(type default)
			)
			(layer "F.SilkS")
		)
		(fp_line
			(start -0.508 -0.9398)
			(end -0.508 0.9398)
			(stroke
				(width 0.1524)
				(type default)
			)
			(layer "F.SilkS")
		)
		(fp_rect
			(start -0.508 0.9398)
			(end 0.508 -0.9398)
			(stroke
				(width 0)
				(type default)
			)
			(fill no)
			(layer "F.CrtYd")
		)
		(fp_rect
			(start -0.508 0.9398)
			(end 0.508 -0.9398)
			(stroke
				(width 0)
				(type default)
			)
			(fill no)
			(layer "F.Fab")
		)
		(pad "1" smd custom
			(at 0 -0.4445 180)
			(size 0.1397 0.1397)
			(layers "F.Cu" "F.Mask" "F.Paste")
			(net "P3V3_M2")
			(options
				(clearance outline)
				(anchor circle)
			)
			(primitives
				(gr_poly
					(pts
						(arc
							(start -0.1778 -0.2794)
							(mid -0.249642 -0.249642)
							(end -0.2794 -0.1778)
						)
						(arc
							(start -0.2794 0.1778)
							(mid -0.249642 0.249642)
							(end -0.1778 0.2794)
						)
						(arc
							(start 0.1778 0.2794)
							(mid 0.249642 0.249642)
							(end 0.2794 0.1778)
						)
						(arc
							(start 0.2794 -0.1778)
							(mid 0.249642 -0.249642)
							(end 0.1778 -0.2794)
						)
					)
					(width 0)
					(fill yes)
				)
			)
		)
		(pad "2" smd custom
			(at 0 0.4445 180)
			(size 0.1397 0.1397)
			(layers "F.Cu" "F.Mask" "F.Paste")
			(net "M2_1_CLKREQ#")
			(options
				(clearance outline)
				(anchor circle)
			)
			(primitives
				(gr_poly
					(pts
						(arc
							(start -0.1778 -0.2794)
							(mid -0.249642 -0.249642)
							(end -0.2794 -0.1778)
						)
						(arc
							(start -0.2794 0.1778)
							(mid -0.249642 0.249642)
							(end -0.1778 0.2794)
						)
						(arc
							(start 0.1778 0.2794)
							(mid 0.249642 0.249642)
							(end 0.2794 0.1778)
						)
						(arc
							(start 0.2794 -0.1778)
							(mid 0.249642 -0.249642)
							(end 0.1778 -0.2794)
						)
					)
					(width 0)
					(fill yes)
				)
			)
		)
	)
	(footprint ""
		(layer "F.Cu")
		(at 27.419046 -157.547056 -90)
		(property "Reference" "R786"
			(at 0 0 270)
			(layer "F.SilkS")
			(hide yes)
			(effects
				(font
					(size 1.27 1.27)
				)
			)
		)
		(property "Value" "0R2J-2-GP"
			(at 0.064008 -3.993896 270)
			(unlocked yes)
			(layer "F.Fab")
			(hide yes)
			(effects
				(font
					(size 1.016 1.016)
					(thickness 0.1524)
				)
			)
		)
		(property "Device Type" "R402H16"
			(at 0.064008 -5.517896 270)
			(unlocked yes)
			(layer "F.Fab")
			(hide yes)
			(effects
				(font
					(size 1.016 1.016)
					(thickness 0.1524)
				)
			)
		)
		(duplicate_pad_numbers_are_jumpers no)
		(fp_line
			(start -0.508 -0.9398)
			(end -0.508 0.9398)
			(stroke
				(width 0.1524)
				(type default)
			)
			(layer "F.SilkS")
		)
		(fp_line
			(start 0.508 -0.9398)
			(end -0.508 -0.9398)
			(stroke
				(width 0.1524)
				(type default)
			)
			(layer "F.SilkS")
		)
		(fp_rect
			(start -0.508 0.9398)
			(end 0.508 -0.9398)
			(stroke
				(width 0)
				(type default)
			)
			(fill no)
			(layer "F.CrtYd")
		)
		(fp_rect
			(start -0.508 0.9398)
			(end 0.508 -0.9398)
			(stroke
				(width 0)
				(type default)
			)
			(fill no)
			(layer "F.Fab")
		)
		(pad "1" smd custom
			(at 0 -0.4445 270)
			(size 0.1397 0.1397)
			(layers "F.Cu" "F.Mask" "F.Paste")
			(net "FLA0_WP_N_R")
			(options
				(clearance outline)
				(anchor circle)
			)
			(primitives
				(gr_poly
					(pts
						(arc
							(start -0.1778 -0.2794)
							(mid -0.249642 -0.249642)
							(end -0.2794 -0.1778)
						)
						(arc
							(start -0.2794 0.1778)
							(mid -0.249642 0.249642)
							(end -0.1778 0.2794)
						)
						(arc
							(start 0.1778 0.2794)
							(mid 0.249642 0.249642)
							(end 0.2794 0.1778)
						)
						(arc
							(start 0.2794 -0.1778)
							(mid 0.249642 -0.249642)
							(end 0.1778 -0.2794)
						)
					)
					(width 0)
					(fill yes)
				)
			)
		)
		(pad "2" smd custom
			(at 0 0.4445 270)
			(size 0.1397 0.1397)
			(layers "F.Cu" "F.Mask" "F.Paste")
			(net "FLA0_WP_N")
			(options
				(clearance outline)
				(anchor circle)
			)
			(primitives
				(gr_poly
					(pts
						(arc
							(start -0.1778 -0.2794)
							(mid -0.249642 -0.249642)
							(end -0.2794 -0.1778)
						)
						(arc
							(start -0.2794 0.1778)
							(mid -0.249642 0.249642)
							(end -0.1778 0.2794)
						)
						(arc
							(start 0.1778 0.2794)
							(mid 0.249642 0.249642)
							(end 0.2794 0.1778)
						)
						(arc
							(start 0.2794 -0.1778)
							(mid 0.249642 -0.249642)
							(end 0.1778 -0.2794)
						)
					)
					(width 0)
					(fill yes)
				)
			)
		)
	)
	(footprint ""
		(layer "F.Cu")
		(at 78.545944 -168.199816 180)
		(property "Reference" "C244"
			(at 0 0 180)
			(layer "F.SilkS")
			(hide yes)
			(effects
				(font
					(size 1.27 1.27)
				)
			)
		)
		(property "Value" "SC10U6D3V5KX-4GP"
			(at -0.0762 -6.1214 180)
			(unlocked yes)
			(layer "F.Fab")
			(hide yes)
			(effects
				(font
					(size 1.016 1.016)
					(thickness 0.1524)
				)
			)
		)
		(property "Device Type" "C805H58"
			(at -0.0762 -8.1534 180)
			(unlocked yes)
			(layer "F.Fab")
			(hide yes)
			(effects
				(font
					(size 1.016 1.016)
					(thickness 0.1524)
				)
			)
		)
		(duplicate_pad_numbers_are_jumpers no)
		(fp_line
			(start 0.635 0)
			(end -0.635 0)
			(stroke
				(width 0.508)
				(type default)
			)
			(layer "F.SilkS")
		)
		(fp_rect
			(start -0.9652 1.778)
			(end 0.9652 -1.778)
			(stroke
				(width 0)
				(type default)
			)
			(fill no)
			(layer "F.CrtYd")
		)
		(fp_poly
			(pts
				(xy -0.9652 -1.778) (xy 0.9652 -1.778) (xy 0.9652 1.778) (xy -0.9652 1.778)
			)
			(stroke
				(width 0)
				(type default)
			)
			(fill no)
			(layer "F.Fab")
		)
		(pad "1" smd rect
			(at 0 -0.9652 180)
			(size 1.397 1.143)
			(layers "F.Cu" "F.Mask" "F.Paste")
			(net "P1V8_STBY")
		)
		(pad "2" smd rect
			(at 0 0.9652 180)
			(size 1.397 1.143)
			(layers "F.Cu" "F.Mask" "F.Paste")
			(net "GND")
		)
	)
	(footprint ""
		(layer "F.Cu")
		(at 224.561908 -102.173024 180)
		(property "Reference" "C671"
			(at 0 0 180)
			(layer "F.SilkS")
			(hide yes)
			(effects
				(font
					(size 1.27 1.27)
				)
			)
		)
		(property "Value" "SC10U16V5KX-7-GP-U"
			(at -0.0762 -6.1214 180)
			(unlocked yes)
			(layer "F.Fab")
			(hide yes)
			(effects
				(font
					(size 1.016 1.016)
					(thickness 0.1524)
				)
			)
		)
		(property "Device Type" "C805H58"
			(at -0.0762 -8.1534 180)
			(unlocked yes)
			(layer "F.Fab")
			(hide yes)
			(effects
				(font
					(size 1.016 1.016)
					(thickness 0.1524)
				)
			)
		)
		(duplicate_pad_numbers_are_jumpers no)
		(fp_line
			(start 0.635 0)
			(end -0.635 0)
			(stroke
				(width 0.508)
				(type default)
			)
			(layer "F.SilkS")
		)
		(fp_rect
			(start -0.9652 1.778)
			(end 0.9652 -1.778)
			(stroke
				(width 0)
				(type default)
			)
			(fill no)
			(layer "F.CrtYd")
		)
		(fp_poly
			(pts
				(xy -0.9652 -1.778) (xy 0.9652 -1.778) (xy 0.9652 1.778) (xy -0.9652 1.778)
			)
			(stroke
				(width 0)
				(type default)
			)
			(fill no)
			(layer "F.Fab")
		)
		(pad "1" smd rect
			(at 0 -0.9652 180)
			(size 1.397 1.143)
			(layers "F.Cu" "F.Mask" "F.Paste")
			(net "P12V_STBY_VIN_U81")
		)
		(pad "2" smd rect
			(at 0 0.9652 180)
			(size 1.397 1.143)
			(layers "F.Cu" "F.Mask" "F.Paste")
			(net "GND")
		)
	)
	(footprint ""
		(layer "F.Cu")
		(at 31.9024 -159.258)
		(property "Reference" "C89"
			(at 0 0 0)
			(layer "F.SilkS")
			(hide yes)
			(effects
				(font
					(size 1.27 1.27)
				)
			)
		)
		(property "Value" "SC4D7U25V5KX-1-GP"
			(at -0.0762 -6.1214 0)
			(unlocked yes)
			(layer "F.Fab")
			(hide yes)
			(effects
				(font
					(size 1.016 1.016)
					(thickness 0.1524)
				)
			)
		)
		(property "Device Type" "C805H58"
			(at -0.0762 -8.1534 0)
			(unlocked yes)
			(layer "F.Fab")
			(hide yes)
			(effects
				(font
					(size 1.016 1.016)
					(thickness 0.1524)
				)
			)
		)
		(duplicate_pad_numbers_are_jumpers no)
		(fp_line
			(start 0.635 0)
			(end -0.635 0)
			(stroke
				(width 0.508)
				(type default)
			)
			(layer "F.SilkS")
		)
		(fp_rect
			(start -0.9652 1.778)
			(end 0.9652 -1.778)
			(stroke
				(width 0)
				(type default)
			)
			(fill no)
			(layer "F.CrtYd")
		)
		(fp_poly
			(pts
				(xy -0.9652 -1.778) (xy 0.9652 -1.778) (xy 0.9652 1.778) (xy -0.9652 1.778)
			)
			(stroke
				(width 0)
				(type default)
			)
			(fill no)
			(layer "F.Fab")
		)
		(pad "1" smd rect
			(at 0 -0.9652)
			(size 1.397 1.143)
			(layers "F.Cu" "F.Mask" "F.Paste")
			(net "DACAV33")
		)
		(pad "2" smd rect
			(at 0 0.9652)
			(size 1.397 1.143)
			(layers "F.Cu" "F.Mask" "F.Paste")
			(net "GND")
		)
	)
	(footprint ""
		(layer "F.Cu")
		(at 98.933 -155.9306 90)
		(property "Reference" "R23"
			(at 0 0 90)
			(layer "F.SilkS")
			(hide yes)
			(effects
				(font
					(size 1.27 1.27)
				)
			)
		)
		(property "Value" "4K7R2F-GP"
			(at 0.064008 -3.993896 90)
			(unlocked yes)
			(layer "F.Fab")
			(hide yes)
			(effects
				(font
					(size 1.016 1.016)
					(thickness 0.1524)
				)
			)
		)
		(property "Device Type" "R402H16"
			(at 0.064008 -5.517896 90)
			(unlocked yes)
			(layer "F.Fab")
			(hide yes)
			(effects
				(font
					(size 1.016 1.016)
					(thickness 0.1524)
				)
			)
		)
		(duplicate_pad_numbers_are_jumpers no)
		(fp_line
			(start 0.508 -0.9398)
			(end -0.508 -0.9398)
			(stroke
				(width 0.1524)
				(type default)
			)
			(layer "F.SilkS")
		)
		(fp_line
			(start -0.508 -0.9398)
			(end -0.508 0.9398)
			(stroke
				(width 0.1524)
				(type default)
			)
			(layer "F.SilkS")
		)
		(fp_rect
			(start -0.508 0.9398)
			(end 0.508 -0.9398)
			(stroke
				(width 0)
				(type default)
			)
			(fill no)
			(layer "F.CrtYd")
		)
		(fp_rect
			(start -0.508 0.9398)
			(end 0.508 -0.9398)
			(stroke
				(width 0)
				(type default)
			)
			(fill no)
			(layer "F.Fab")
		)
		(pad "1" smd custom
			(at 0 -0.4445 90)
			(size 0.1397 0.1397)
			(layers "F.Cu" "F.Mask" "F.Paste")
			(net "CFG_SEL0")
			(options
				(clearance outline)
				(anchor circle)
			)
			(primitives
				(gr_poly
					(pts
						(arc
							(start -0.1778 -0.2794)
							(mid -0.249642 -0.249642)
							(end -0.2794 -0.1778)
						)
						(arc
							(start -0.2794 0.1778)
							(mid -0.249642 0.249642)
							(end -0.1778 0.2794)
						)
						(arc
							(start 0.1778 0.2794)
							(mid 0.249642 0.249642)
							(end 0.2794 0.1778)
						)
						(arc
							(start 0.2794 -0.1778)
							(mid 0.249642 -0.249642)
							(end 0.1778 -0.2794)
						)
					)
					(width 0)
					(fill yes)
				)
			)
		)
		(pad "2" smd custom
			(at 0 0.4445 90)
			(size 0.1397 0.1397)
			(layers "F.Cu" "F.Mask" "F.Paste")
			(net "GND")
			(options
				(clearance outline)
				(anchor circle)
			)
			(primitives
				(gr_poly
					(pts
						(arc
							(start -0.1778 -0.2794)
							(mid -0.249642 -0.249642)
							(end -0.2794 -0.1778)
						)
						(arc
							(start -0.2794 0.1778)
							(mid -0.249642 0.249642)
							(end -0.1778 0.2794)
						)
						(arc
							(start 0.1778 0.2794)
							(mid 0.249642 0.249642)
							(end 0.2794 0.1778)
						)
						(arc
							(start 0.2794 -0.1778)
							(mid 0.249642 -0.249642)
							(end 0.1778 -0.2794)
						)
					)
					(width 0)
					(fill yes)
				)
			)
		)
	)
	(footprint ""
		(layer "F.Cu")
		(at 36.986718 -187.972192 -90)
		(property "Reference" "C180"
			(at 0 0 270)
			(layer "F.SilkS")
			(hide yes)
			(effects
				(font
					(size 1.27 1.27)
				)
			)
		)
		(property "Value" "SC2200P50V2KX-2GP"
			(at 1.1811 -2.7051 270)
			(unlocked yes)
			(layer "F.Fab")
			(hide yes)
			(effects
				(font
					(size 1.016 1.016)
					(thickness 0.1524)
				)
			)
		)
		(property "Device Type" "C402H22"
			(at 1.1811 -4.2291 270)
			(unlocked yes)
			(layer "F.Fab")
			(hide yes)
			(effects
				(font
					(size 1.016 1.016)
					(thickness 0.1524)
				)
			)
		)
		(duplicate_pad_numbers_are_jumpers no)
		(fp_rect
			(start -0.4318 0.9525)
			(end 0.4318 -0.9525)
			(stroke
				(width 0)
				(type default)
			)
			(fill no)
			(layer "F.CrtYd")
		)
		(fp_rect
			(start -0.4318 0.9525)
			(end 0.4318 -0.9525)
			(stroke
				(width 0)
				(type default)
			)
			(fill no)
			(layer "F.Fab")
		)
		(pad "1" smd custom
			(at 0 -0.4445 270)
			(size 0.1524 0.1524)
			(layers "F.Cu" "F.Mask" "F.Paste")
			(net "P3V3_STBY_LL")
			(options
				(clearance outline)
				(anchor circle)
			)
			(primitives
				(gr_poly
					(pts
						(arc
							(start 0.3048 -0.2032)
							(mid 0.275042 -0.275042)
							(end 0.2032 -0.3048)
						)
						(arc
							(start -0.2032 -0.3048)
							(mid -0.275042 -0.275042)
							(end -0.3048 -0.2032)
						)
						(arc
							(start -0.3048 0.2032)
							(mid -0.275042 0.275042)
							(end -0.2032 0.3048)
						)
						(arc
							(start 0.2032 0.3048)
							(mid 0.275042 0.275042)
							(end 0.3048 0.2032)
						)
					)
					(width 0)
					(fill yes)
				)
			)
		)
		(pad "2" smd custom
			(at 0 0.4445 270)
			(size 0.1524 0.1524)
			(layers "F.Cu" "F.Mask" "F.Paste")
			(net "P3V3_SNB")
			(options
				(clearance outline)
				(anchor circle)
			)
			(primitives
				(gr_poly
					(pts
						(arc
							(start 0.3048 -0.2032)
							(mid 0.275042 -0.275042)
							(end 0.2032 -0.3048)
						)
						(arc
							(start -0.2032 -0.3048)
							(mid -0.275042 -0.275042)
							(end -0.3048 -0.2032)
						)
						(arc
							(start -0.3048 0.2032)
							(mid -0.275042 0.275042)
							(end -0.2032 0.3048)
						)
						(arc
							(start 0.2032 0.3048)
							(mid 0.275042 0.275042)
							(end 0.3048 0.2032)
						)
					)
					(width 0)
					(fill yes)
				)
			)
		)
	)
	(footprint ""
		(layer "F.Cu")
		(at 88.768428 -48.203612 90)
		(property "Reference" "C189"
			(at 0 0 90)
			(layer "F.SilkS")
			(hide yes)
			(effects
				(font
					(size 1.27 1.27)
				)
			)
		)
		(property "Value" "SCD1U25V2KX-2-GP"
			(at 1.1811 -2.7051 90)
			(unlocked yes)
			(layer "F.Fab")
			(hide yes)
			(effects
				(font
					(size 1.016 1.016)
					(thickness 0.1524)
				)
			)
		)
		(property "Device Type" "C402H22"
			(at 1.1811 -4.2291 90)
			(unlocked yes)
			(layer "F.Fab")
			(hide yes)
			(effects
				(font
					(size 1.016 1.016)
					(thickness 0.1524)
				)
			)
		)
		(duplicate_pad_numbers_are_jumpers no)
		(fp_rect
			(start -0.4318 0.9525)
			(end 0.4318 -0.9525)
			(stroke
				(width 0)
				(type default)
			)
			(fill no)
			(layer "F.CrtYd")
		)
		(fp_rect
			(start -0.4318 0.9525)
			(end 0.4318 -0.9525)
			(stroke
				(width 0)
				(type default)
			)
			(fill no)
			(layer "F.Fab")
		)
		(pad "1" smd custom
			(at 0 -0.4445 90)
			(size 0.1524 0.1524)
			(layers "F.Cu" "F.Mask" "F.Paste")
			(net "P3V3")
			(options
				(clearance outline)
				(anchor circle)
			)
			(primitives
				(gr_poly
					(pts
						(arc
							(start 0.3048 -0.2032)
							(mid 0.275042 -0.275042)
							(end 0.2032 -0.3048)
						)
						(arc
							(start -0.2032 -0.3048)
							(mid -0.275042 -0.275042)
							(end -0.3048 -0.2032)
						)
						(arc
							(start -0.3048 0.2032)
							(mid -0.275042 0.275042)
							(end -0.2032 0.3048)
						)
						(arc
							(start 0.2032 0.3048)
							(mid 0.275042 0.275042)
							(end 0.3048 0.2032)
						)
					)
					(width 0)
					(fill yes)
				)
			)
		)
		(pad "2" smd custom
			(at 0 0.4445 90)
			(size 0.1524 0.1524)
			(layers "F.Cu" "F.Mask" "F.Paste")
			(net "GND")
			(options
				(clearance outline)
				(anchor circle)
			)
			(primitives
				(gr_poly
					(pts
						(arc
							(start 0.3048 -0.2032)
							(mid 0.275042 -0.275042)
							(end 0.2032 -0.3048)
						)
						(arc
							(start -0.2032 -0.3048)
							(mid -0.275042 -0.275042)
							(end -0.3048 -0.2032)
						)
						(arc
							(start -0.3048 0.2032)
							(mid -0.275042 0.275042)
							(end -0.2032 0.3048)
						)
						(arc
							(start 0.2032 0.3048)
							(mid 0.275042 0.275042)
							(end 0.3048 0.2032)
						)
					)
					(width 0)
					(fill yes)
				)
			)
		)
	)
)
